FILE_TYPE = MACRO_DRAWING;
SET COLOR_WIRE YELLOW;
SET COLOR_PROP MONO;
SET COLOR_DOT WHITE;
SET COLOR_ARC YELLOW;
SET COLOR_BODY GREEN;
SET COLOR_NOTE MONO;
SET PROP_DISPLAY VALUE;
SET PAGE_NUMBER P261;
FORCEADD INTEL_CORP_BPAGE..1
(-1125 1625);
FORCEPROP 1 LAST CDS_CON_LAST_MODIFIED Fri Jun 16 17:49:38 2017
J 0
(-2550 1950);
PAINT ORANGE (-2550 1950);
DISPLAY INVISIBLE (-2550 1950);
FORCEPROP 1 LAST CUSTOM_TXT_CDS <CURRENT_DESIGN_SHEET> OF <TOTAL_DESIGN_SHEETS>
J 0
(-1625 1650);
PAINT ORANGE (-1625 1650);
FORCEPROP 2 LAST CUSTOM_TXT_CDS <XR_PAGE_TITLE>
J 0
(-9015 6875);
DISPLAY 0.638298 (-9015 6875);
PAINT PINK (-9015 6875);
DISPLAY INVISIBLE (-9015 6875);
FORCEPROP 2 LAST CUSTOM_TXT_CDS <CON_LAST_MODIFIED>
J 0
(-5125 1725);
PAINT ORANGE (-5125 1725);
FORCEPROP 1 LAST SCH_TITLE TPM BLOCK DIAGRAM
J 0
(-9075 1675);
DISPLAY 2.468085 (-9075 1675);
PAINT ORANGE (-9075 1675);
FORCEPROP 2 LAST PAGE_BORDER TRUE
J 0
(-9015 6875);
DISPLAY 0.638298 (-9015 6875);
PAINT PINK (-9015 6875);
DISPLAY INVISIBLE (-9015 6875);
FORCEPROP 2 LAST CDS_LIB mstr_symbols
J 0
(-1125 1625);
PAINT MONO (-1125 1625);
DISPLAY INVISIBLE (-1125 1625);
FORCEPROP 1 LAST COMMENT_BODY TRUE
J 0
(-1113 1637);
DISPLAY 0.468085 (-1113 1637);
PAINT GREEN (-1113 1637);
DISPLAY INVISIBLE (-1113 1637);
FORCEPROP 2 LAST CDS_XR_PAGE_TITLE CR-265 : @BASEBOARD_FAB2_LIB.BASEBOARD_FAB2(SCH_1):PAGE265
J 0
(-9015 6875);
DISPLAY 0.638298 (-9015 6875);
PAINT PINK (-9015 6875);
DISPLAY INVISIBLE (-9015 6875);
FORCENOTE
$CDS_IMAGE|TPM Block diagram_20161011.jpg|7999|6000
(-5125 4050) 0;
DISPLAY LEFT (-5125 4050);
QUIT
